(kicad_pcb
	(version 20221018)
	(generator pcbnew)
	(general
    (thickness 1.6)
  )
	(paper "A4")
	(title_block
    (title "NUC Computer Cluster Power Breakout HW")
    (date "2023-10-18")
    (rev "1.4.3")
    (company "Antmicro Ltd.")
		(comment 9 "footprints 166-170 of 234")
	)
	(layers
    (0 "F.Cu" mixed)
    (1 "In1.Cu" power)
    (2 "In2.Cu" mixed)
    (31 "B.Cu" power)
    (32 "B.Adhes" user "B.Adhesive")
    (33 "F.Adhes" user "F.Adhesive")
    (34 "B.Paste" user)
    (35 "F.Paste" user)
    (36 "B.SilkS" user "B.Silkscreen")
    (37 "F.SilkS" user "F.Silkscreen")
    (38 "B.Mask" user)
    (39 "F.Mask" user)
    (40 "Dwgs.User" user "User.Drawings")
    (41 "Cmts.User" user "User.Comments")
    (42 "Eco1.User" user "User.Eco1")
    (43 "Eco2.User" user "User.Eco2")
    (44 "Edge.Cuts" user)
    (45 "Margin" user)
    (46 "B.CrtYd" user "B.Courtyard")
    (47 "F.CrtYd" user "F.Courtyard")
    (48 "B.Fab" user)
    (49 "F.Fab" user)
  )
	(footprint "antmicro-footprints:Vishay_PowerPAK_1212-8_Single" (layer "F.Cu")
    (at 167.3 87.2 90)
    (descr "PowerPAK 1212-8 Single")
    (tags "Vishay PowerPAK 1212-8 Single")
    (property "Author" "Antmicro")
    (property "License" "Apache-2.0")
    (property "MPN" "SI7613DN-T1-GE3")
    (property "Manufacturer" "Vishay")
    (property "Sheetfile" "power-switch.kicad_sch")
    (property "Sheetname" "Power switch 4")
    (property "ki_description" "Power MOSFET, P Channel, 20 V, 35 A, 0.0072 ohm, PowerPAK 1212, Surface Mount")
    (property "ki_keywords" "SMT, TRANSISTOR, SEMICONDUCTOR, MOSFET, PMOS")
    (attr smd)
    (fp_text reference "QA4" (at -2.95 -1.05 180) (layer "F.SilkS")
        (effects (font (size 0.7 0.7) (thickness 0.15)) (justify left bottom))
    )
    (fp_text value "SI7613DN-T1-GE3" (at 0 2.7 90) (layer "F.Fab")
        (effects (font (size 0.7 0.7) (thickness 0.15)) (justify left bottom))
    )
    (fp_text user "Author: Antmicro" (at -8 5.9 90) (layer "F.Fab") hide
        (effects (font (size 0.7 0.7) (thickness 0.15)) (justify left bottom))
    )
    (fp_text user "${REFERENCE}" (at -8 4.7 90) (layer "F.Fab") hide
        (effects (font (size 0.7 0.7) (thickness 0.15)) (justify left bottom))
    )
    (fp_text user "License: Apache-2.0" (at -8 7.1 90) (layer "F.Fab") hide
        (effects (font (size 0.7 0.7) (thickness 0.15)) (justify left bottom))
    )
    (fp_line (start -1.651 -1.651) (end -1.651 -1.317)
      (stroke (width 0.15) (type solid)) (layer "F.SilkS"))
    (fp_line (start -1.651 -1.651) (end 1.648 -1.651)
      (stroke (width 0.15) (type solid)) (layer "F.SilkS"))
    (fp_line (start -1.635 1.3) (end -1.635 1.634)
      (stroke (width 0.15) (type solid)) (layer "F.SilkS"))
    (fp_line (start -1.635 1.634) (end 1.634 1.634)
      (stroke (width 0.15) (type solid)) (layer "F.SilkS"))
    (fp_line (start 1.634 1.3) (end 1.634 1.634)
      (stroke (width 0.15) (type solid)) (layer "F.SilkS"))
    (fp_line (start 1.648 -1.651) (end 1.648 -1.317)
      (stroke (width 0.15) (type solid)) (layer "F.SilkS"))
    (fp_circle (center -1.9 -1.4) (end -1.85 -1.4)
      (stroke (width 0.15) (type solid)) (fill solid) (layer "F.SilkS"))
    (fp_rect (start -2 -1.8) (end 2 1.798)
      (stroke (width 0.05) (type solid)) (fill none) (layer "F.CrtYd"))
    (fp_line (start -1.6425 -1.4175) (end -1.4175 -1.6425)
      (stroke (width 0.15) (type solid)) (layer "F.Fab"))
    (fp_rect (start -1.651 -1.651) (end 1.648 1.648)
      (stroke (width 0.15) (type solid)) (fill none) (layer "F.Fab"))
    (pad "1" smd rect (at -1.436 -0.99 90) (size 0.99 0.405) (layers "F.Cu" "F.Paste" "F.Mask")
      (net 11 "VCC12V0") (pinfunction "S") (pintype "passive"))
    (pad "2" smd rect (at -1.436 -0.332 90) (size 0.99 0.405) (layers "F.Cu" "F.Paste" "F.Mask")
      (net 11 "VCC12V0") (pinfunction "S") (pintype "passive"))
    (pad "3" smd rect (at -1.436 0.33 90) (size 0.99 0.405) (layers "F.Cu" "F.Paste" "F.Mask")
      (net 11 "VCC12V0") (pinfunction "S") (pintype "passive"))
    (pad "4" smd rect (at -1.436 0.988 90) (size 0.99 0.405) (layers "F.Cu" "F.Paste" "F.Mask")
      (net 96 "Net-(QA4-G)") (pinfunction "G") (pintype "passive"))
    (pad "5" smd custom (at 0.557 0 90) (size 1.725 2.235) (layers "F.Cu" "F.Paste" "F.Mask")
      (net 27 "C_MEAS_4") (pinfunction "D") (pintype "passive") (zone_connect 2)
      (options (clearance outline) (anchor rect))
      (primitives
        (gr_poly
          (pts
            (xy 0.8625 0.1275)
            (xy 0.8625 -0.1275)
            (xy 1.3725 -0.1275)
            (xy 1.3725 -0.5325)
            (xy 0.8625 -0.5325)
            (xy 0.8625 -0.7875)
            (xy 1.3725 -0.7875)
            (xy 1.3725 -1.195)
            (xy 0.6125 -1.195)
            (xy 0.6125 1.195)
            (xy 1.3725 1.195)
            (xy 1.3725 0.7875)
            (xy 0.8625 0.7875)
            (xy 0.8625 0.5325)
            (xy 1.3725 0.5325)
            (xy 1.3725 0.1275)
          )
          (width 0) (fill yes))
      ))
  )
	(footprint "antmicro-footprints:LED_0603_1608Metric_G" (layer "F.Cu")
    (at 145.9 53.85)
    (descr "LED SMD 0603 Green")
    (tags "LED SMD 0603 Green")
    (property "Author" "Antmicro")
    (property "Color" "Green")
    (property "License" "Apache-2.0")
    (property "MPN" "LG L29K-G2J1-24-Z")
    (property "Manufacturer" "OSRAM")
    (property "Sheetfile" "d1600e-psu-breakout-board.kicad_sch")
    (property "Sheetname" "")
    (property "ki_description" "LED, Green, SMD, 0603, 20 mA, 1.7 V, 570 nm")
    (property "ki_keywords" "SMT, DIODE, SEMICONDUCTOR, LED")
    (zone_connect 1)
    (attr smd)
    (fp_text reference "D6" (at -0.85 1.65) (layer "F.SilkS")
        (effects (font (size 0.7 0.7) (thickness 0.15)) (justify left bottom))
    )
    (fp_text value "LED_G_0603_LG_L29K-G2J1-24-Z" (at -0.001 1.599) (layer "F.Fab")
        (effects (font (size 0.7 0.7) (thickness 0.15)) (justify left bottom))
    )
    (fp_text user "License: Apache-2.0" (at -1.4224 3.599) (layer "F.Fab") hide
        (effects (font (size 0.7 0.7) (thickness 0.15)) (justify left bottom))
    )
    (fp_text user "${REFERENCE}" (at -1.4224 5.999) (layer "F.Fab") hide
        (effects (font (size 0.7 0.7) (thickness 0.15)) (justify left bottom))
    )
    (fp_text user "Author: Antmicro" (at -1.4224 4.799) (layer "F.Fab") hide
        (effects (font (size 0.7 0.7) (thickness 0.15)) (justify left bottom))
    )
    (fp_line (start -1.18 -0.319) (end -1.18 0.321)
      (stroke (width 0.15) (type solid)) (layer "F.SilkS"))
    (fp_line (start -0.094672 0.001008) (end -0.24 0.001008)
      (stroke (width 0.1) (type solid)) (layer "F.SilkS"))
    (fp_line (start -0.094672 0.001008) (end 0.105328 -0.198992)
      (stroke (width 0.1) (type solid)) (layer "F.SilkS"))
    (fp_line (start -0.094672 0.201008) (end -0.094672 -0.198992)
      (stroke (width 0.1) (type solid)) (layer "F.SilkS"))
    (fp_line (start 0.105328 0.001008) (end 0.24 0.001)
      (stroke (width 0.1) (type solid)) (layer "F.SilkS"))
    (fp_line (start 0.105328 0.201008) (end -0.094672 0.001008)
      (stroke (width 0.1) (type solid)) (layer "F.SilkS"))
    (fp_line (start 0.105328 0.201008) (end 0.105328 -0.198992)
      (stroke (width 0.1) (type solid)) (layer "F.SilkS"))
    (fp_line (start 0.22 -0.35) (end -0.22 -0.35)
      (stroke (width 0.15) (type solid)) (layer "F.SilkS"))
    (fp_line (start 0.22 0.35) (end -0.22 0.35)
      (stroke (width 0.15) (type solid)) (layer "F.SilkS"))
    (fp_rect (start 1.25 0.65) (end -1.25 -0.65)
      (stroke (width 0.05) (type solid)) (fill none) (layer "F.CrtYd"))
    (fp_line (start -0.199 -0.202) (end -0.199 0.1)
      (stroke (width 0.15) (type solid)) (layer "F.Fab"))
    (fp_line (start -0.199 0) (end -0.597 0)
      (stroke (width 0.15) (type solid)) (layer "F.Fab"))
    (fp_line (start -0.199 0.2) (end -0.199 0.1)
      (stroke (width 0.15) (type solid)) (layer "F.Fab"))
    (fp_line (start -0.101 0) (end 0.201 0.2)
      (stroke (width 0.15) (type solid)) (layer "F.Fab"))
    (fp_line (start 0.201 -0.202) (end -0.101 0)
      (stroke (width 0.15) (type solid)) (layer "F.Fab"))
    (fp_line (start 0.201 0) (end 0.201 -0.202)
      (stroke (width 0.15) (type solid)) (layer "F.Fab"))
    (fp_line (start 0.201 0.2) (end 0.201 0)
      (stroke (width 0.15) (type solid)) (layer "F.Fab"))
    (fp_line (start 0.599 0) (end 0.201 0)
      (stroke (width 0.15) (type solid)) (layer "F.Fab"))
    (fp_rect (start 0.848 0.4) (end -0.85 -0.402)
      (stroke (width 0.15) (type solid)) (fill none) (layer "F.Fab"))
    (pad "1" smd roundrect (at -0.7 0 180) (size 0.8 1) (layers "F.Cu" "F.Paste" "F.Mask") (roundrect_rratio 0.2)
      (net 4 "GND") (pinfunction "C") (pintype "passive"))
    (pad "2" smd roundrect (at 0.7 0 180) (size 0.8 1) (layers "F.Cu" "F.Paste" "F.Mask") (roundrect_rratio 0.2)
      (net 40 "Net-(D6-A)") (pinfunction "A") (pintype "passive"))
  )
	(footprint "antmicro-footprints:PinHeader_1x3_P2.54mm_Drill1.1mm" (layer "F.Cu")
    (at 105.85 81.29 90)
    (property "Author" "Antmicro")
    (property "License" "Apache-2.0")
    (property "MPN" "61300311121")
    (property "Manufacturer" "Würth Elektronik")
    (property "Sheetfile" "daughterboard-supply.kicad_sch")
    (property "Sheetname" "daughterboard-supply")
    (property "ki_description" "Pin Header, Vertical, Board-to-Board, 2.54 mm, 1 Rows, 3 Contacts, Through Hole Straight, WR-PHD")
    (property "ki_keywords" "VERTICAL, THT, HEADER, CONNECTOR, MALE")
    (attr through_hole)
    (fp_text reference "SW1" (at 0 0 90) (layer "F.SilkS") hide
        (effects (font (size 0.7 0.7) (thickness 0.15)))
    )
    (fp_text value "PinHeader_1x3_P2.54mm_Drill1.1mm" (at 0 0 90) (layer "F.SilkS") hide
        (effects (font (size 1.524 1.524) (thickness 0.05)))
    )
    (fp_text user "License: Apache-2.0" (at -1.6 6.6 90) (layer "F.Fab") hide
        (effects (font (size 0.7 0.7) (thickness 0.15)) (justify left bottom))
    )
    (fp_text user "${REFERENCE}" (at -1.6 4 90) (layer "F.Fab") hide
        (effects (font (size 0.7 0.7) (thickness 0.15)) (justify left bottom))
    )
    (fp_text user "Author: Antmicro" (at -1.6 5.2 90) (layer "F.Fab") hide
        (effects (font (size 0.7 0.7) (thickness 0.15)) (justify left bottom))
    )
    (fp_line (start -1.401 -1.401) (end -1.401 -0.902)
      (stroke (width 0.15) (type solid)) (layer "F.SilkS"))
    (fp_line (start -1.401 -1.401) (end -0.902 -1.401)
      (stroke (width 0.15) (type solid)) (layer "F.SilkS"))
    (fp_line (start -1.401 1.398) (end -1.401 0.9)
      (stroke (width 0.15) (type solid)) (layer "F.SilkS"))
    (fp_line (start -1.401 1.398) (end -0.902 1.398)
      (stroke (width 0.15) (type solid)) (layer "F.SilkS"))
    (fp_line (start 6.499 -1.401) (end 5.999 -1.401)
      (stroke (width 0.15) (type solid)) (layer "F.SilkS"))
    (fp_line (start 6.499 -1.401) (end 6.499 -0.902)
      (stroke (width 0.15) (type solid)) (layer "F.SilkS"))
    (fp_line (start 6.499 1.398) (end 5.999 1.398)
      (stroke (width 0.15) (type solid)) (layer "F.SilkS"))
    (fp_line (start 6.499 1.398) (end 6.499 0.9)
      (stroke (width 0.15) (type solid)) (layer "F.SilkS"))
    (fp_line (start -1.52 -1.52) (end -1.52 1.5)
      (stroke (width 0.05) (type solid)) (layer "F.CrtYd"))
    (fp_line (start -1.52 -1.52) (end 6.58 -1.52)
      (stroke (width 0.05) (type solid)) (layer "F.CrtYd"))
    (fp_line (start -1.52 1.5) (end 6.58 1.5)
      (stroke (width 0.05) (type solid)) (layer "F.CrtYd"))
    (fp_line (start 6.58 -1.52) (end 6.58 1.5)
      (stroke (width 0.05) (type solid)) (layer "F.CrtYd"))
    (fp_line (start -1.27 -1.27) (end -1.27 1.269)
      (stroke (width 0.15) (type solid)) (layer "F.Fab"))
    (fp_line (start -1.27 -1.27) (end 6.349 -1.27)
      (stroke (width 0.15) (type solid)) (layer "F.Fab"))
    (fp_line (start -1.27 1.269) (end 6.349 1.269)
      (stroke (width 0.15) (type solid)) (layer "F.Fab"))
    (fp_line (start 6.349 -1.27) (end 6.349 1.269)
      (stroke (width 0.15) (type solid)) (layer "F.Fab"))
    (pad "1" thru_hole rect (at 0 0 90) (size 1.7 1.7) (drill 1.1) (layers "*.Cu" "*.Mask")
      (net 2 "VCC5V0") (pintype "passive"))
    (pad "2" thru_hole circle (at 2.539 0 90) (size 1.7 1.7) (drill 1.1) (layers "*.Cu" "*.Mask")
      (net 137 "Net-(J9-Pad8)") (pintype "passive"))
    (pad "3" thru_hole circle (at 5.078 0 90) (size 1.7 1.7) (drill 1.1) (layers "*.Cu" "*.Mask")
      (net 4 "GND") (pintype "passive"))
  )
	(footprint "antmicro-footprints:TP_SMD_1mm" (layer "F.Cu")
    (at 184.2 111.15)
    (property "Author" "Antmicro")
    (property "License" "Apache-2.0")
    (property "MPN" "")
    (property "Manufacturer" "")
    (property "Sheetfile" "ftdi-module.kicad_sch")
    (property "Sheetname" "FTDI")
    (property "exclude_from_bom" "")
    (property "ki_description" "Test point 1mm SMD")
    (property "ki_keywords" "TESTPOINT")
    (attr exclude_from_pos_files exclude_from_bom)
    (fp_text reference "TP2" (at 0.65 -0.6 90) (layer "F.SilkS")
        (effects (font (size 0.7 0.7) (thickness 0.15)) (justify left bottom))
    )
    (fp_text value "TP_1mm_SMD" (at 0 1.4) (layer "F.Fab")
        (effects (font (size 0.7 0.7) (thickness 0.15)) (justify left bottom))
    )
    (fp_text user "${REFERENCE}" (at -0.5 2.8) (layer "F.Fab") hide
        (effects (font (size 0.7 0.7) (thickness 0.15)) (justify left bottom))
    )
    (fp_text user "License: Apache-2.0" (at -0.5 5.2) (layer "F.Fab") hide
        (effects (font (size 0.7 0.7) (thickness 0.15)) (justify left bottom))
    )
    (fp_text user "Author: Antmicro" (at -0.5 4) (layer "F.Fab") hide
        (effects (font (size 0.7 0.7) (thickness 0.15)) (justify left bottom))
    )
    (fp_circle (center 0 0) (end 0.6 0)
      (stroke (width 0.05) (type default)) (fill none) (layer "F.CrtYd"))
    (pad "1" smd circle (at 0 0) (size 1 1) (layers "F.Cu" "F.Mask")
      (net 117 "Net-(U1-SBU_{1})") (pinfunction "1") (pintype "passive"))
  )
	(footprint "antmicro-footprints:Conn_Molex_KK_1x4_22-27-2041" (layer "F.Cu")
    (at 134.81 53.75)
    (property "Author" "Antmicro")
    (property "License" "Apache-2.0")
    (property "MPN" "22-27-2041")
    (property "Manufacturer" "Molex")
    (property "Sheetfile" "d1600e-psu-breakout-board.kicad_sch")
    (property "Sheetname" "")
    (property "ki_description" "Rectangular connector (header, female pins)")
    (property "ki_keywords" "VERTICAL, THT, HEADER, CONNECTOR, MALE")
    (attr through_hole)
    (fp_text reference "J12" (at 4.64 4.325) (layer "F.SilkS")
        (effects (font (size 0.7 0.7) (thickness 0.15)) (justify left bottom))
    )
    (fp_text value "Molex_KK_1x4_22-27-2041" (at -0.8 4.6 180) (layer "F.Fab")
        (effects (font (size 0.7 0.7) (thickness 0.15)) (justify left bottom))
    )
    (fp_text user "${REFERENCE}" (at -2.12 9.15) (layer "F.Fab") hide
        (effects (font (size 0.7 0.7) (thickness 0.15)) (justify left bottom))
    )
    (fp_text user "License: Apache-2.0" (at -2.12 7.95) (layer "F.Fab") hide
        (effects (font (size 0.7 0.7) (thickness 0.15)) (justify left bottom))
    )
    (fp_text user "Author: Antmicro" (at -2.12 6.75) (layer "F.Fab") hide
        (effects (font (size 0.7 0.7) (thickness 0.15)) (justify left bottom))
    )
    (fp_line (start -1.39 -3.03) (end -1.39 2.99)
      (stroke (width 0.15) (type solid)) (layer "F.SilkS"))
    (fp_line (start -1.39 2.99) (end 8.99 2.99)
      (stroke (width 0.15) (type solid)) (layer "F.SilkS"))
    (fp_line (start -0.81 -3.03) (end -0.81 -2.43)
      (stroke (width 0.15) (type solid)) (layer "F.SilkS"))
    (fp_line (start -0.81 -2.43) (end 0.79 -2.43)
      (stroke (width 0.15) (type solid)) (layer "F.SilkS"))
    (fp_line (start -0.01 1.99) (end 0.24 1.46)
      (stroke (width 0.15) (type solid)) (layer "F.SilkS"))
    (fp_line (start -0.01 1.99) (end 7.61 1.99)
      (stroke (width 0.15) (type solid)) (layer "F.SilkS"))
    (fp_line (start -0.01 2.99) (end -0.01 1.99)
      (stroke (width 0.15) (type solid)) (layer "F.SilkS"))
    (fp_line (start 0.24 1.46) (end 7.36 1.46)
      (stroke (width 0.15) (type solid)) (layer "F.SilkS"))
    (fp_line (start 0.24 2.99) (end 0.24 1.99)
      (stroke (width 0.15) (type solid)) (layer "F.SilkS"))
    (fp_line (start 0.79 -2.43) (end 0.79 -3.03)
      (stroke (width 0.15) (type solid)) (layer "F.SilkS"))
    (fp_line (start 1.73 -3.03) (end 1.73 -2.43)
      (stroke (width 0.15) (type solid)) (layer "F.SilkS"))
    (fp_line (start 1.73 -2.43) (end 3.33 -2.43)
      (stroke (width 0.15) (type solid)) (layer "F.SilkS"))
    (fp_line (start 3.33 -2.43) (end 3.33 -3.03)
      (stroke (width 0.15) (type solid)) (layer "F.SilkS"))
    (fp_line (start 4.27 -3.03) (end 4.27 -2.43)
      (stroke (width 0.15) (type solid)) (layer "F.SilkS"))
    (fp_line (start 4.27 -2.43) (end 5.87 -2.43)
      (stroke (width 0.15) (type solid)) (layer "F.SilkS"))
    (fp_line (start 5.87 -2.43) (end 5.87 -3.03)
      (stroke (width 0.15) (type solid)) (layer "F.SilkS"))
    (fp_line (start 6.81 -3.03) (end 6.81 -2.43)
      (stroke (width 0.15) (type solid)) (layer "F.SilkS"))
    (fp_line (start 6.81 -2.43) (end 8.41 -2.43)
      (stroke (width 0.15) (type solid)) (layer "F.SilkS"))
    (fp_line (start 7.36 1.46) (end 7.61 1.99)
      (stroke (width 0.15) (type solid)) (layer "F.SilkS"))
    (fp_line (start 7.36 2.99) (end 7.36 1.99)
      (stroke (width 0.15) (type solid)) (layer "F.SilkS"))
    (fp_line (start 7.61 1.99) (end 7.61 2.99)
      (stroke (width 0.15) (type solid)) (layer "F.SilkS"))
    (fp_line (start 8.41 -2.43) (end 8.41 -3.03)
      (stroke (width 0.15) (type solid)) (layer "F.SilkS"))
    (fp_line (start 8.99 -3.03) (end -1.39 -3.03)
      (stroke (width 0.15) (type solid)) (layer "F.SilkS"))
    (fp_line (start 8.99 2.99) (end 8.99 -3.03)
      (stroke (width 0.15) (type solid)) (layer "F.SilkS"))
    (fp_line (start -1.79 -3.38) (end -1.79 3.42)
      (stroke (width 0.05) (type solid)) (layer "F.CrtYd"))
    (fp_line (start -1.79 3.42) (end 9.37 3.42)
      (stroke (width 0.05) (type solid)) (layer "F.CrtYd"))
    (fp_line (start 9.37 -3.38) (end -1.79 -3.38)
      (stroke (width 0.05) (type solid)) (layer "F.CrtYd"))
    (fp_line (start 9.37 3.42) (end 9.37 -3.38)
      (stroke (width 0.05) (type solid)) (layer "F.CrtYd"))
    (fp_line (start -1.29 -2.88) (end -1.29 2.92)
      (stroke (width 0.15) (type solid)) (layer "F.Fab"))
    (fp_line (start -1.29 2.92) (end 8.87 2.92)
      (stroke (width 0.15) (type solid)) (layer "F.Fab"))
    (fp_line (start 8.163 0) (end 8.87 -0.5)
      (stroke (width 0.15) (type solid)) (layer "F.Fab"))
    (fp_line (start 8.87 -2.88) (end -1.29 -2.88)
      (stroke (width 0.15) (type solid)) (layer "F.Fab"))
    (fp_line (start 8.87 0.5) (end 8.163 0)
      (stroke (width 0.15) (type solid)) (layer "F.Fab"))
    (fp_line (start 8.87 2.92) (end 8.87 -2.88)
      (stroke (width 0.15) (type solid)) (layer "F.Fab"))
    (pad "1" thru_hole roundrect (at 0 0) (size 1.74 2.19) (drill 1.19) (layers "*.Cu" "*.Mask") (roundrect_rratio 0.143678)
      (net 11 "VCC12V0") (pintype "passive"))
    (pad "2" thru_hole oval (at 2.54 0) (size 1.74 2.19) (drill 1.19) (layers "*.Cu" "*.Mask")
      (net 4 "GND") (pintype "passive"))
    (pad "3" thru_hole oval (at 5.08 0) (size 1.74 2.19) (drill 1.19) (layers "*.Cu" "*.Mask")
      (net 4 "GND") (pintype "passive"))
    (pad "4" thru_hole oval (at 7.62 0) (size 1.74 2.19) (drill 1.19) (layers "*.Cu" "*.Mask")
      (net 2 "VCC5V0") (pintype "passive"))
  )
)
